# T6G (Grand Teton) — schematic netlist excerpt (pin names and nets, part order shuffled) for the footprints in the layout excerpt that follows; sources: Cadence DE-HDL packaged netlist, KiCad conversion of 04192023_DAF0TMB3IC0_F0TG_MB_C_brd_V02_OCP.brd

C6051  Q_CAP  0.01UF 50V 10% X7R  pkg C0402  page 177 : A = P3V3_AUX ; B = GND
C2144  Q_CAP  22UF 4V 20% X6S  pkg C0402  page 68 : A = PVDDCR_SOC_P0 ; B = GND

(kicad_pcb
	(version 20260206)
	(generator "pcbnew")
	(generator_version "10.0")
	(general
		(thickness 1.6)
		(legacy_teardrops no)
	)
	(paper "A4")
	(title_block
		(title "04192023_DAF0TMB3IC0_F0TG_MB_C_brd_V02_OCP.brd")
		(comment 1 "Grand Teton / footprints 5974-5975 of 8354")
	)
	(layers
		(0 "F.Cu" signal "TOP")
		(4 "In1.Cu" signal "GND")
		(6 "In2.Cu" signal "IN1")
		(8 "In3.Cu" signal "GND1")
		(10 "In4.Cu" signal "IN2")
		(12 "In5.Cu" signal "GND2")
		(14 "In6.Cu" signal "IN3")
		(16 "In7.Cu" signal "GND3")
		(18 "In8.Cu" signal "VCC")
		(20 "In9.Cu" signal "VCC1")
		(22 "In10.Cu" signal "GND4")
		(24 "In11.Cu" signal "IN4")
		(26 "In12.Cu" signal "GND5")
		(28 "In13.Cu" signal "IN5")
		(30 "In14.Cu" signal "GND6")
		(32 "In15.Cu" signal "IN6")
		(34 "In16.Cu" signal "GND7")
		(2 "B.Cu" signal "BOTTOM")
		(9 "F.Adhes" user "F.Adhesive")
		(11 "B.Adhes" user "B.Adhesive")
		(13 "F.Paste" user "Package Geometry/Pastemask Top")
		(15 "B.Paste" user "Package Geometry/Pastemask Bottom")
		(5 "F.SilkS" user "Ref Des/Silkscreen Top")
		(7 "B.SilkS" user "Ref Des/Silkscreen Bottom")
		(1 "F.Mask" user "Board Geometry/Soldermask Top")
		(3 "B.Mask" user "Board Geometry/Soldermask Bottom")
		(17 "Dwgs.User" user "User.Drawings")
		(19 "Cmts.User" user "User.Comments")
		(21 "Eco1.User" user "User.Eco1")
		(23 "Eco2.User" user "User.Eco2")
		(25 "Edge.Cuts" user "Board Geometry/Outline")
		(27 "Margin" user)
		(31 "F.CrtYd" user "Package Geometry/Place Bound Top")
		(29 "B.CrtYd" user "Package Geometry/Place Bound Bottom")
		(35 "F.Fab" user "Ref Des/Assembly Top")
		(33 "B.Fab" user "Ref Des/Assembly Bottom")
	)
	(footprint ""
		(layer "B.Cu")
		(at 131.849114 -31.421578 -90)
		(property "Reference" "C6051"
			(at 0 0 90)
			(layer "B.SilkS")
			(hide yes)
			(effects
				(font
					(size 1.27 1.27)
				)
				(justify mirror)
			)
		)
		(property "Value" ""
			(at 0 0 90)
			(layer "B.Fab")
			(effects
				(font
					(size 1.27 1.27)
				)
				(justify mirror)
			)
		)
		(duplicate_pad_numbers_are_jumpers no)
		(fp_line
			(start -0.7874 0.4064)
			(end 0.7874 0.4064)
			(stroke
				(width 0.1524)
				(type default)
			)
			(layer "B.SilkS")
		)
		(fp_line
			(start 0.7874 0.4064)
			(end 0.7874 -0.4064)
			(stroke
				(width 0.1524)
				(type default)
			)
			(layer "B.SilkS")
		)
		(fp_line
			(start -0.7874 -0.4064)
			(end -0.7874 0.4064)
			(stroke
				(width 0.1524)
				(type default)
			)
			(layer "B.SilkS")
		)
		(fp_line
			(start 0.7874 -0.4064)
			(end -0.7874 -0.4064)
			(stroke
				(width 0.1524)
				(type default)
			)
			(layer "B.SilkS")
		)
		(fp_line
			(start -0.67945 0.3048)
			(end -0.120396 0.3048)
			(stroke
				(width 0.1)
				(type default)
			)
			(layer "B.Fab")
		)
		(fp_line
			(start -0.120396 0.3048)
			(end -0.120396 0.2794)
			(stroke
				(width 0.1)
				(type default)
			)
			(layer "B.Fab")
		)
		(fp_line
			(start 0.12065 0.3048)
			(end 0.67945 0.3048)
			(stroke
				(width 0.1)
				(type default)
			)
			(layer "B.Fab")
		)
		(fp_line
			(start 0.67945 0.3048)
			(end 0.67945 -0.305054)
			(stroke
				(width 0.1)
				(type default)
			)
			(layer "B.Fab")
		)
		(fp_line
			(start -0.120396 0.2794)
			(end 0.12065 0.2794)
			(stroke
				(width 0.1)
				(type default)
			)
			(layer "B.Fab")
		)
		(fp_line
			(start 0.12065 0.2794)
			(end 0.12065 0.3048)
			(stroke
				(width 0.1)
				(type default)
			)
			(layer "B.Fab")
		)
		(fp_line
			(start -0.12065 -0.2794)
			(end -0.12065 -0.3048)
			(stroke
				(width 0.1)
				(type default)
			)
			(layer "B.Fab")
		)
		(fp_line
			(start 0.12065 -0.2794)
			(end -0.12065 -0.2794)
			(stroke
				(width 0.1)
				(type default)
			)
			(layer "B.Fab")
		)
		(fp_line
			(start -0.67945 -0.3048)
			(end -0.67945 0.3048)
			(stroke
				(width 0.1)
				(type default)
			)
			(layer "B.Fab")
		)
		(fp_line
			(start -0.12065 -0.3048)
			(end -0.67945 -0.3048)
			(stroke
				(width 0.1)
				(type default)
			)
			(layer "B.Fab")
		)
		(fp_line
			(start 0.12065 -0.305054)
			(end 0.12065 -0.2794)
			(stroke
				(width 0.1)
				(type default)
			)
			(layer "B.Fab")
		)
		(fp_line
			(start 0.67945 -0.305054)
			(end 0.12065 -0.305054)
			(stroke
				(width 0.1)
				(type default)
			)
			(layer "B.Fab")
		)
		(pad "1" smd circle
			(at 0.40005 0 90)
			(size 0 0)
			(layers "B.Cu" "B.Mask" "B.Paste")
			(net "P3V3_AUX")
		)
		(pad "2" smd circle
			(at -0.40005 0 90)
			(size 0 0)
			(layers "B.Cu" "B.Mask" "B.Paste")
			(net "GND")
		)
	)
	(footprint ""
		(layer "B.Cu")
		(at 359.721404 -253.43231 180)
		(property "Reference" "C2144"
			(at 0 0 0)
			(layer "B.SilkS")
			(hide yes)
			(effects
				(font
					(size 1.27 1.27)
				)
				(justify mirror)
			)
		)
		(property "Value" ""
			(at 0 0 0)
			(layer "B.Fab")
			(effects
				(font
					(size 1.27 1.27)
				)
				(justify mirror)
			)
		)
		(duplicate_pad_numbers_are_jumpers no)
		(fp_line
			(start 0.7874 0.4064)
			(end 0.7874 -0.4064)
			(stroke
				(width 0.1524)
				(type default)
			)
			(layer "B.SilkS")
		)
		(fp_line
			(start 0.7874 -0.4064)
			(end -0.7874 -0.4064)
			(stroke
				(width 0.1524)
				(type default)
			)
			(layer "B.SilkS")
		)
		(fp_line
			(start -0.7874 0.4064)
			(end 0.7874 0.4064)
			(stroke
				(width 0.1524)
				(type default)
			)
			(layer "B.SilkS")
		)
		(fp_line
			(start -0.7874 -0.4064)
			(end -0.7874 0.4064)
			(stroke
				(width 0.1524)
				(type default)
			)
			(layer "B.SilkS")
		)
		(fp_line
			(start 0.67945 0.3048)
			(end 0.67945 -0.305054)
			(stroke
				(width 0.1)
				(type default)
			)
			(layer "B.Fab")
		)
		(fp_line
			(start 0.67945 -0.305054)
			(end 0.12065 -0.305054)
			(stroke
				(width 0.1)
				(type default)
			)
			(layer "B.Fab")
		)
		(fp_line
			(start 0.12065 0.3048)
			(end 0.67945 0.3048)
			(stroke
				(width 0.1)
				(type default)
			)
			(layer "B.Fab")
		)
		(fp_line
			(start 0.12065 0.2794)
			(end 0.12065 0.3048)
			(stroke
				(width 0.1)
				(type default)
			)
			(layer "B.Fab")
		)
		(fp_line
			(start 0.12065 -0.2794)
			(end -0.12065 -0.2794)
			(stroke
				(width 0.1)
				(type default)
			)
			(layer "B.Fab")
		)
		(fp_line
			(start 0.12065 -0.305054)
			(end 0.12065 -0.2794)
			(stroke
				(width 0.1)
				(type default)
			)
			(layer "B.Fab")
		)
		(fp_line
			(start -0.120396 0.3048)
			(end -0.120396 0.2794)
			(stroke
				(width 0.1)
				(type default)
			)
			(layer "B.Fab")
		)
		(fp_line
			(start -0.120396 0.2794)
			(end 0.12065 0.2794)
			(stroke
				(width 0.1)
				(type default)
			)
			(layer "B.Fab")
		)
		(fp_line
			(start -0.12065 -0.2794)
			(end -0.12065 -0.3048)
			(stroke
				(width 0.1)
				(type default)
			)
			(layer "B.Fab")
		)
		(fp_line
			(start -0.12065 -0.3048)
			(end -0.67945 -0.3048)
			(stroke
				(width 0.1)
				(type default)
			)
			(layer "B.Fab")
		)
		(fp_line
			(start -0.67945 0.3048)
			(end -0.120396 0.3048)
			(stroke
				(width 0.1)
				(type default)
			)
			(layer "B.Fab")
		)
		(fp_line
			(start -0.67945 -0.3048)
			(end -0.67945 0.3048)
			(stroke
				(width 0.1)
				(type default)
			)
			(layer "B.Fab")
		)
		(pad "1" smd circle
			(at 0.40005 0)
			(size 0 0)
			(layers "B.Cu" "B.Mask" "B.Paste")
			(net "PVDDCR_SOC_P0")
		)
		(pad "2" smd circle
			(at -0.40005 0)
			(size 0 0)
			(layers "B.Cu" "B.Mask" "B.Paste")
			(net "GND")
		)
	)
)
